# BASEBOARD_FAB2 (Tioga Pass) — schematic netlist excerpt (pin names and nets, part order shuffled) for the footprints in the layout excerpt that follows; sources: Cadence DE-HDL packaged netlist, KiCad conversion of Wiwynn_Tioga_Pass_MB.brd

J9M1  SCONN288_H44441003  SCONN  pkg PIP  page 84
  \12v\(1)  = P12V_NVDIMM_KLM
  VSS(93)  = GND
  DQ(4)  = M_K_DQ<4>
  VSS(92)  = GND
  DQ(0)  = M_K_DQ<0>
  VSS(91)  = GND
  DQS9P  = M_K_DQS_DP<9>
  DQS9N  = M_K_DQS_DN<9>
  VSS(90)  = GND
  DQ(6)  = M_K_DQ<6>
  VSS(89)  = GND
  DQ(2)  = M_K_DQ<2>
  VSS(88)  = GND
  DQ(12)  = M_K_DQ<12>
  VSS(87)  = GND
  DQ(8)  = M_K_DQ<8>
  VSS(86)  = GND
  DQS10P  = M_K_DQS_DP<10>
  DQS10N  = M_K_DQS_DN<10>
  VSS(85)  = GND
  DQ(14)  = M_K_DQ<14>
  VSS(84)  = GND
  DQ(10)  = M_K_DQ<10>
  VSS(83)  = GND
  DQ(20)  = M_K_DQ<20>
  VSS(82)  = GND
  DQ(16)  = M_K_DQ<16>
  VSS(81)  = GND
  DQS11P  = M_K_DQS_DP<11>
  DQS11N  = M_K_DQS_DN<11>
  VSS(80)  = GND
  DQ(22)  = M_K_DQ<22>
  VSS(79)  = GND
  DQ(18)  = M_K_DQ<18>
  VSS(78)  = GND
  DQ(28)  = M_K_DQ<28>
  VSS(77)  = GND
  DQ(24)  = M_K_DQ<24>
  VSS(76)  = GND
  DQS12P  = M_K_DQS_DP<12>
  DQS12N  = M_K_DQS_DN<12>
  VSS(75)  = GND
  DQ(30)  = M_K_DQ<30>
  VSS(74)  = GND
  DQ(26)  = M_K_DQ<26>
  VSS(73)  = GND
  CB(4)  = M_K_ECC<4>
  VSS(72)  = GND
  CB(0)  = M_K_ECC<0>
  VSS(71)  = GND
  DQS17P  = M_K_DQS_DP<17>
  DQS17N  = M_K_DQS_DN<17>
  VSS(70)  = GND
  CB(6)  = M_K_ECC<6>
  VSS(69)  = GND
  CB(2)  = M_K_ECC<2>
  VSS(68)  = GND
  RESET_N  = M_KLM_RST_N
  VDD(25)  = PVDDQ_KLM
  CKE(0)  = M_K_CKE<2>
  VDD(24)  = PVDDQ_KLM
  ACT_N  = M_K_ACT_N
  BG(0)  = M_K_BG<0>
  VDD(23)  = PVDDQ_KLM
  A12  = M_K_MA<12>
  A9  = M_K_MA<9>
  VDD(22)  = PVDDQ_KLM
  A8  = M_K_MA<8>
  A6  = M_K_MA<6>
  VDD(21)  = PVDDQ_KLM
  A3  = M_K_MA<3>
  A1  = M_K_MA<1>
  VDD(20)  = PVDDQ_KLM
  CK0P  = M_K_CLK_DP<2>
  CK0N  = M_K_CLK_DN<2>
  VDD(19)  = PVDDQ_KLM
  VTT(1)  = PVTT_KLM
  EVENT_N  = FM_DIMM_EVENT_COD_N
  A0  = M_K_MA<0>
  VDD(18)  = PVDDQ_KLM
  BA(0)  = M_K_BA<0>
  A16_RAS_N  = M_K_MA<16>
  VDD(17)  = PVDDQ_KLM
  S0_N  = M_K_CS_N<4>
  VDD(16)  = PVDDQ_KLM
  A15_CAS_N  = M_K_MA<15>
  ODT(0)  = M_K_ODT<2>
  VDD(15)  = PVDDQ_KLM
  S1_N  = M_K_CS_N<5>
  VDD(14)  = PVDDQ_KLM
  ODT(1)  = M_K_ODT<3>
  VDD(13)  = PVDDQ_KLM
  S2_N_C(0)  = M_K_CS_N<6>
  VSS(67)  = GND
  DQ(36)  = M_K_DQ<36>
  VSS(66)  = GND
  DQ(32)  = M_K_DQ<32>
  VSS(65)  = GND
  DQS13P  = M_K_DQS_DP<13>
  DQS13N  = M_K_DQS_DN<13>
  VSS(64)  = GND
  DQ(38)  = M_K_DQ<38>
  VSS(63)  = GND
  DQ(34)  = M_K_DQ<34>
  VSS(62)  = GND
  DQ(44)  = M_K_DQ<44>
  VSS(61)  = GND
  DQ(40)  = M_K_DQ<40>
  VSS(60)  = GND
  DQS14P  = M_K_DQS_DP<14>
  DQS14N  = M_K_DQS_DN<14>
  VSS(59)  = GND
  DQ(46)  = M_K_DQ<46>
  VSS(58)  = GND
  DQ(42)  = M_K_DQ<42>
  VSS(57)  = GND
  DQ(52)  = M_K_DQ<52>
  VSS(56)  = GND
  DQ(48)  = M_K_DQ<48>
  VSS(55)  = GND
  DQS15P  = M_K_DQS_DP<15>
  DQS15N  = M_K_DQS_DN<15>
  VSS(54)  = GND
  DQ(54)  = M_K_DQ<54>
  VSS(53)  = GND
  DQ(50)  = M_K_DQ<50>
  VSS(52)  = GND
  DQ(60)  = M_K_DQ<60>
  VSS(51)  = GND
  DQ(56)  = M_K_DQ<56>
  VSS(50)  = GND
  DQS16P  = M_K_DQS_DP<16>
  DQS16N  = M_K_DQS_DN<16>
  VSS(49)  = GND
  DQ(62)  = M_K_DQ<62>
  VSS(48)  = GND
  DQ(58)  = M_K_DQ<58>
  VSS(47)  = GND
  SA(0)  = PVPP_KLM
  SA(1)  = GND
  SCL  = SMB_DDR_KLM_VPP_SCL
  VPP(4)  = PVPP_KLM
  VPP(3)  = PVPP_KLM
  RFU(2)  = TP_CH_K_DIMM0_RFU_2
  \12v\(0)  = P12V_NVDIMM_KLM
  VREFCA  = M_K_VREF
  VSS(46)  = GND
  DQ(5)  = M_K_DQ<5>
  VSS(45)  = GND
  DQ(1)  = M_K_DQ<1>
  VSS(44)  = GND
  DQS0N  = M_K_DQS_DN<0>
  DQS0P  = M_K_DQS_DP<0>
  VSS(43)  = GND
  DQ(7)  = M_K_DQ<7>
  VSS(42)  = GND
  DQ(3)  = M_K_DQ<3>
  VSS(41)  = GND
  DQ(13)  = M_K_DQ<13>
  VSS(40)  = GND
  DQ(9)  = M_K_DQ<9>
  VSS(39)  = GND
  DQS1N  = M_K_DQS_DN<1>
  DQS1P  = M_K_DQS_DP<1>
  VSS(38)  = GND
  DQ(15)  = M_K_DQ<15>
  VSS(37)  = GND
  DQ(11)  = M_K_DQ<11>
  VSS(36)  = GND
  DQ(21)  = M_K_DQ<21>
  VSS(35)  = GND
  DQ(17)  = M_K_DQ<17>
  VSS(34)  = GND
  DQS2N  = M_K_DQS_DN<2>
  DQS2P  = M_K_DQS_DP<2>
  VSS(33)  = GND
  DQ(23)  = M_K_DQ<23>
  VSS(32)  = GND
  DQ(19)  = M_K_DQ<19>
  VSS(31)  = GND
  DQ(29)  = M_K_DQ<29>
  VSS(30)  = GND
  DQ(25)  = M_K_DQ<25>
  VSS(29)  = GND
  DQS3N  = M_K_DQS_DN<3>
  DQS3P  = M_K_DQS_DP<3>
  VSS(28)  = GND
  DQ(31)  = M_K_DQ<31>
  VSS(27)  = GND
  DQ(27)  = M_K_DQ<27>
  VSS(26)  = GND
  CB(5)  = M_K_ECC<5>
  VSS(25)  = GND
  CB(1)  = M_K_ECC<1>
  VSS(24)  = GND
  DQS8N  = M_K_DQS_DN<8>
  DQS8P  = M_K_DQS_DP<8>
  VSS(23)  = GND
  CB(7)  = M_K_ECC<7>
  VSS(22)  = GND
  CB(3)  = M_K_ECC<3>
  VSS(21)  = GND
  CKE(1)  = M_K_CKE<3>
  VDD(12)  = PVDDQ_KLM
  RFU(0)  = TP_CH_K_DIMM0_RFU_0
  VDD(11)  = PVDDQ_KLM
  BG(1)  = M_K_BG<1>
  ALERT_N  = M_K_ALERT_N
  VDD(10)  = PVDDQ_KLM
  A11  = M_K_MA<11>
  A7  = M_K_MA<7>
  VDD(9)  = PVDDQ_KLM
  A5  = M_K_MA<5>
  A4  = M_K_MA<4>
  VDD(8)  = PVDDQ_KLM
  A2  = M_K_MA<2>
  VDD(7)  = PVDDQ_KLM
  CK1P  = M_K_CLK_DP<3>
  CK1N  = M_K_CLK_DN<3>
  VDD(6)  = PVDDQ_KLM
  VTT(0)  = PVTT_KLM
  PAR  = M_K_PAR
  VDD(5)  = PVDDQ_KLM
  BA(1)  = M_K_BA<1>
  A10  = M_K_MA<10>
  VDD(4)  = PVDDQ_KLM
  RFU(1)  = TP_CH_K_DIMM0_RFU_1
  A14_WE_N  = M_K_MA<14>
  VDD(3)  = PVDDQ_KLM
  SAVE_N_NC  = FM_ADR_COMPLETE_KLM_N
  VDD(2)  = PVDDQ_KLM
  A13  = M_K_MA<13>
  VDD(1)  = PVDDQ_KLM
  A17  = M_K_MA<17>
  C(2)  = M_K_C<2>
  VDD(0)  = PVDDQ_KLM
  S3_N_C(1)  = M_K_CS_N<7>
  SA(2)  = GND
  VSS(20)  = GND
  DQ(37)  = M_K_DQ<37>
  VSS(19)  = GND
  DQ(33)  = M_K_DQ<33>
  VSS(18)  = GND
  DQS4N  = M_K_DQS_DN<4>
  DQS4P  = M_K_DQS_DP<4>
  VSS(17)  = GND
  DQ(39)  = M_K_DQ<39>
  VSS(16)  = GND
  DQ(35)  = M_K_DQ<35>
  VSS(15)  = GND
  DQ(45)  = M_K_DQ<45>
  VSS(14)  = GND
  DQ(41)  = M_K_DQ<41>
  VSS(13)  = GND
  DQS5N  = M_K_DQS_DN<5>
  DQS5P  = M_K_DQS_DP<5>
  VSS(12)  = GND
  DQ(47)  = M_K_DQ<47>
  VSS(11)  = GND
  DQ(43)  = M_K_DQ<43>
  VSS(10)  = GND
  DQ(53)  = M_K_DQ<53>
  VSS(9)  = GND
  DQ(49)  = M_K_DQ<49>
  VSS(8)  = GND
  DQS6N  = M_K_DQS_DN<6>
  DQS6P  = M_K_DQS_DP<6>
  VSS(7)  = GND
  DQ(55)  = M_K_DQ<55>
  VSS(6)  = GND
  DQ(51)  = M_K_DQ<51>
  VSS(5)  = GND
  DQ(61)  = M_K_DQ<61>
  VSS(4)  = GND
  DQ(57)  = M_K_DQ<57>
  VSS(3)  = GND
  DQS7N  = M_K_DQS_DN<7>
  DQS7P  = M_K_DQS_DP<7>
  VSS(2)  = GND
  DQ(63)  = M_K_DQ<63>
  VSS(1)  = GND
  DQ(59)  = M_K_DQ<59>
  VSS(0)  = GND
  VDDSPD  = PVPP_KLM
  SDA  = SMB_DDR_KLM_VPP_SDA
  VPP(1)  = PVPP_KLM
  VPP(0)  = PVPP_KLM
  VPP(2)  = PVPP_KLM

(kicad_pcb
	(version 20260206)
	(generator "pcbnew")
	(generator_version "10.0")
	(general
		(thickness 1.6)
		(legacy_teardrops no)
	)
	(paper "A4")
	(title_block
		(title "Wiwynn_Tioga_Pass_MB.brd")
		(comment 1 "Tioga Pass / footprint 2445 of 4770 (J9M1), pads 202-249 of 291")
	)
	(layers
		(0 "F.Cu" signal "TOP")
		(4 "In1.Cu" signal "L2GND")
		(6 "In2.Cu" signal "L3")
		(8 "In3.Cu" signal "L4GND")
		(10 "In4.Cu" signal "L5")
		(12 "In5.Cu" signal "L6GND")
		(14 "In6.Cu" signal "L7VCC")
		(16 "In7.Cu" signal "L8VCC")
		(18 "In8.Cu" signal "L9GND")
		(20 "In9.Cu" signal "L10")
		(22 "In10.Cu" signal "L11GND")
		(24 "In11.Cu" signal "L12")
		(26 "In12.Cu" signal "L13GND")
		(2 "B.Cu" signal "BOTTOM")
		(9 "F.Adhes" user "F.Adhesive")
		(11 "B.Adhes" user "B.Adhesive")
		(13 "F.Paste" user "Package Geometry/Pastemask Top")
		(15 "B.Paste" user "Package Geometry/Pastemask Bottom")
		(5 "F.SilkS" user "Ref Des/Silkscreen Top")
		(7 "B.SilkS" user "Ref Des/Silkscreen Bottom")
		(1 "F.Mask" user "Board Geometry/Soldermask Top")
		(3 "B.Mask" user "Board Geometry/Soldermask Bottom")
		(17 "Dwgs.User" user "User.Drawings")
		(19 "Cmts.User" user "User.Comments")
		(21 "Eco1.User" user "User.Eco1")
		(23 "Eco2.User" user "User.Eco2")
		(25 "Edge.Cuts" user "Board Geometry/Outline")
		(27 "Margin" user)
		(31 "F.CrtYd" user "Package Geometry/Place Bound Top")
		(29 "B.CrtYd" user "Package Geometry/Place Bound Bottom")
		(35 "F.Fab" user "Ref Des/Assembly Top")
		(33 "B.Fab" user "Ref Des/Assembly Bottom")
	)
	(footprint ""
		(layer "B.Cu")
		(at 29.699458 -132.876036 90)
		(property "Reference" "J9M1"
			(at 2.352548 37.991542 0)
			(unlocked yes)
			(layer "B.SilkS")
			(effects
				(font
					(size 0.7874 0.5842)
					(thickness 0.1524)
				)
				(justify left mirror)
			)
		)
		(property "Value" ""
			(at 0 0 90)
			(layer "B.Fab")
			(effects
				(font
					(size 1.27 1.27)
				)
				(justify mirror)
			)
		)
		(duplicate_pad_numbers_are_jumpers no)
		(pad "199" smd rect
			(at -4.59994 45.900086 270)
			(size 1.8034 0.508)
			(layers "B.Cu" "B.Mask" "B.Paste")
			(net "M_K_ECC<7>")
		)
		(pad "200" smd rect
			(at -4.59994 46.74997 270)
			(size 1.8034 0.508)
			(layers "B.Cu" "B.Mask" "B.Paste")
			(net "GND")
		)
		(pad "201" smd rect
			(at -4.59994 47.600108 270)
			(size 1.8034 0.508)
			(layers "B.Cu" "B.Mask" "B.Paste")
			(net "M_K_ECC<3>")
		)
		(pad "202" smd rect
			(at -4.59994 48.449992 270)
			(size 1.8034 0.508)
			(layers "B.Cu" "B.Mask" "B.Paste")
			(net "GND")
		)
		(pad "203" smd rect
			(at -4.59994 49.299876 270)
			(size 1.8034 0.508)
			(layers "B.Cu" "B.Mask" "B.Paste")
			(net "M_K_CKE<3>")
		)
		(pad "204" smd rect
			(at -4.59994 50.150014 270)
			(size 1.8034 0.508)
			(layers "B.Cu" "B.Mask" "B.Paste")
			(net "PVDDQ_KLM")
		)
		(pad "205" smd rect
			(at -4.59994 50.999898 270)
			(size 1.8034 0.508)
			(layers "B.Cu" "B.Mask" "B.Paste")
			(net "TP_CH_K_DIMM0_RFU_0")
		)
		(pad "206" smd rect
			(at -4.59994 51.850036 270)
			(size 1.8034 0.508)
			(layers "B.Cu" "B.Mask" "B.Paste")
			(net "PVDDQ_KLM")
		)
		(pad "207" smd rect
			(at -4.59994 52.69992 270)
			(size 1.8034 0.508)
			(layers "B.Cu" "B.Mask" "B.Paste")
			(net "M_K_BG<1>")
		)
		(pad "208" smd rect
			(at -4.59994 53.550058 270)
			(size 1.8034 0.508)
			(layers "B.Cu" "B.Mask" "B.Paste")
			(net "M_K_ALERT_N")
		)
		(pad "209" smd rect
			(at -4.59994 54.399942 270)
			(size 1.8034 0.508)
			(layers "B.Cu" "B.Mask" "B.Paste")
			(net "PVDDQ_KLM")
		)
		(pad "210" smd rect
			(at -4.59994 55.25008 270)
			(size 1.8034 0.508)
			(layers "B.Cu" "B.Mask" "B.Paste")
			(net "M_K_MA<11>")
		)
		(pad "211" smd rect
			(at -4.59994 56.099964 270)
			(size 1.8034 0.508)
			(layers "B.Cu" "B.Mask" "B.Paste")
			(net "M_K_MA<7>")
		)
		(pad "212" smd rect
			(at -4.59994 56.950102 270)
			(size 1.8034 0.508)
			(layers "B.Cu" "B.Mask" "B.Paste")
			(net "PVDDQ_KLM")
		)
		(pad "213" smd rect
			(at -4.59994 57.799986 270)
			(size 1.8034 0.508)
			(layers "B.Cu" "B.Mask" "B.Paste")
			(net "M_K_MA<5>")
		)
		(pad "214" smd rect
			(at -4.59994 58.650124 270)
			(size 1.8034 0.508)
			(layers "B.Cu" "B.Mask" "B.Paste")
			(net "M_K_MA<4>")
		)
		(pad "215" smd rect
			(at -4.59994 59.500008 270)
			(size 1.8034 0.508)
			(layers "B.Cu" "B.Mask" "B.Paste")
			(net "PVDDQ_KLM")
		)
		(pad "216" smd rect
			(at -4.59994 60.349892 270)
			(size 1.8034 0.508)
			(layers "B.Cu" "B.Mask" "B.Paste")
			(net "M_K_MA<2>")
		)
		(pad "217" smd rect
			(at -4.59994 61.20003 270)
			(size 1.8034 0.508)
			(layers "B.Cu" "B.Mask" "B.Paste")
			(net "PVDDQ_KLM")
		)
		(pad "218" smd rect
			(at -4.59994 62.049914 270)
			(size 1.8034 0.508)
			(layers "B.Cu" "B.Mask" "B.Paste")
			(net "M_K_CLK_DP<3>")
		)
		(pad "219" smd rect
			(at -4.59994 62.900052 270)
			(size 1.8034 0.508)
			(layers "B.Cu" "B.Mask" "B.Paste")
			(net "M_K_CLK_DN<3>")
		)
		(pad "220" smd rect
			(at -4.59994 63.749936 270)
			(size 1.8034 0.508)
			(layers "B.Cu" "B.Mask" "B.Paste")
			(net "PVDDQ_KLM")
		)
		(pad "221" smd rect
			(at -4.59994 64.600074 270)
			(size 1.8034 0.508)
			(layers "B.Cu" "B.Mask" "B.Paste")
			(net "PVTT_KLM")
		)
		(pad "222" smd rect
			(at -4.59994 70.550024 270)
			(size 1.8034 0.508)
			(layers "B.Cu" "B.Mask" "B.Paste")
			(net "M_K_PAR")
		)
		(pad "223" smd rect
			(at -4.59994 71.399908 270)
			(size 1.8034 0.508)
			(layers "B.Cu" "B.Mask" "B.Paste")
			(net "PVDDQ_KLM")
		)
		(pad "224" smd rect
			(at -4.59994 72.250046 270)
			(size 1.8034 0.508)
			(layers "B.Cu" "B.Mask" "B.Paste")
			(net "M_K_BA<1>")
		)
		(pad "225" smd rect
			(at -4.59994 73.09993 270)
			(size 1.8034 0.508)
			(layers "B.Cu" "B.Mask" "B.Paste")
			(net "M_K_MA<10>")
		)
		(pad "226" smd rect
			(at -4.59994 73.950068 270)
			(size 1.8034 0.508)
			(layers "B.Cu" "B.Mask" "B.Paste")
			(net "PVDDQ_KLM")
		)
		(pad "227" smd rect
			(at -4.59994 74.799952 270)
			(size 1.8034 0.508)
			(layers "B.Cu" "B.Mask" "B.Paste")
			(net "TP_CH_K_DIMM0_RFU_1")
		)
		(pad "228" smd rect
			(at -4.59994 75.65009 270)
			(size 1.8034 0.508)
			(layers "B.Cu" "B.Mask" "B.Paste")
			(net "M_K_MA<14>")
		)
		(pad "229" smd rect
			(at -4.59994 76.499974 270)
			(size 1.8034 0.508)
			(layers "B.Cu" "B.Mask" "B.Paste")
			(net "PVDDQ_KLM")
		)
		(pad "230" smd rect
			(at -4.59994 77.350112 270)
			(size 1.8034 0.508)
			(layers "B.Cu" "B.Mask" "B.Paste")
			(net "FM_ADR_COMPLETE_KLM_N")
		)
		(pad "231" smd rect
			(at -4.59994 78.199996 270)
			(size 1.8034 0.508)
			(layers "B.Cu" "B.Mask" "B.Paste")
			(net "PVDDQ_KLM")
		)
		(pad "232" smd rect
			(at -4.59994 79.04988 270)
			(size 1.8034 0.508)
			(layers "B.Cu" "B.Mask" "B.Paste")
			(net "M_K_MA<13>")
		)
		(pad "233" smd rect
			(at -4.59994 79.900018 270)
			(size 1.8034 0.508)
			(layers "B.Cu" "B.Mask" "B.Paste")
			(net "PVDDQ_KLM")
		)
		(pad "234" smd rect
			(at -4.59994 80.749902 270)
			(size 1.8034 0.508)
			(layers "B.Cu" "B.Mask" "B.Paste")
			(net "M_K_MA<17>")
		)
		(pad "235" smd rect
			(at -4.59994 81.60004 270)
			(size 1.8034 0.508)
			(layers "B.Cu" "B.Mask" "B.Paste")
			(net "M_K_C<2>")
		)
		(pad "236" smd rect
			(at -4.59994 82.449924 270)
			(size 1.8034 0.508)
			(layers "B.Cu" "B.Mask" "B.Paste")
			(net "PVDDQ_KLM")
		)
		(pad "237" smd rect
			(at -4.59994 83.300062 270)
			(size 1.8034 0.508)
			(layers "B.Cu" "B.Mask" "B.Paste")
			(net "M_K_CS_N<7>")
		)
		(pad "238" smd rect
			(at -4.59994 84.149946 270)
			(size 1.8034 0.508)
			(layers "B.Cu" "B.Mask" "B.Paste")
			(net "GND")
		)
		(pad "239" smd rect
			(at -4.59994 85.000084 270)
			(size 1.8034 0.508)
			(layers "B.Cu" "B.Mask" "B.Paste")
			(net "GND")
		)
		(pad "240" smd rect
			(at -4.59994 85.849968 270)
			(size 1.8034 0.508)
			(layers "B.Cu" "B.Mask" "B.Paste")
			(net "M_K_DQ<37>")
		)
		(pad "241" smd rect
			(at -4.59994 86.700106 270)
			(size 1.8034 0.508)
			(layers "B.Cu" "B.Mask" "B.Paste")
			(net "GND")
		)
		(pad "242" smd rect
			(at -4.59994 87.54999 270)
			(size 1.8034 0.508)
			(layers "B.Cu" "B.Mask" "B.Paste")
			(net "M_K_DQ<33>")
		)
		(pad "243" smd rect
			(at -4.59994 88.399874 270)
			(size 1.8034 0.508)
			(layers "B.Cu" "B.Mask" "B.Paste")
			(net "GND")
		)
		(pad "244" smd rect
			(at -4.59994 89.250012 270)
			(size 1.8034 0.508)
			(layers "B.Cu" "B.Mask" "B.Paste")
			(net "M_K_DQS_DN<4>")
		)
		(pad "245" smd rect
			(at -4.59994 90.099896 270)
			(size 1.8034 0.508)
			(layers "B.Cu" "B.Mask" "B.Paste")
			(net "M_K_DQS_DP<4>")
		)
		(pad "246" smd rect
			(at -4.59994 90.950034 270)
			(size 1.8034 0.508)
			(layers "B.Cu" "B.Mask" "B.Paste")
			(net "GND")
		)
	)
)
